(kicad_pcb
	(version 20260206)
	(generator "pcbnew")
	(generator_version "10.0")
	(general
		(thickness 1.6)
		(legacy_teardrops no)
	)
	(paper "A4")
	(title_block
		(title "04192023_DAF0TMB3IC0_F0TG_MB_C_brd_V02_OCP.brd")
		(comment 1 "Grand Teton / footprints 8162-8169 of 8354")
	)
	(layers
		(0 "F.Cu" signal "TOP")
		(4 "In1.Cu" signal "GND")
		(6 "In2.Cu" signal "IN1")
		(8 "In3.Cu" signal "GND1")
		(10 "In4.Cu" signal "IN2")
		(12 "In5.Cu" signal "GND2")
		(14 "In6.Cu" signal "IN3")
		(16 "In7.Cu" signal "GND3")
		(18 "In8.Cu" signal "VCC")
		(20 "In9.Cu" signal "VCC1")
		(22 "In10.Cu" signal "GND4")
		(24 "In11.Cu" signal "IN4")
		(26 "In12.Cu" signal "GND5")
		(28 "In13.Cu" signal "IN5")
		(30 "In14.Cu" signal "GND6")
		(32 "In15.Cu" signal "IN6")
		(34 "In16.Cu" signal "GND7")
		(2 "B.Cu" signal "BOTTOM")
		(9 "F.Adhes" user "F.Adhesive")
		(11 "B.Adhes" user "B.Adhesive")
		(13 "F.Paste" user "Package Geometry/Pastemask Top")
		(15 "B.Paste" user "Package Geometry/Pastemask Bottom")
		(5 "F.SilkS" user "Ref Des/Silkscreen Top")
		(7 "B.SilkS" user "Ref Des/Silkscreen Bottom")
		(1 "F.Mask" user "Board Geometry/Soldermask Top")
		(3 "B.Mask" user "Board Geometry/Soldermask Bottom")
		(17 "Dwgs.User" user "User.Drawings")
		(19 "Cmts.User" user "User.Comments")
		(21 "Eco1.User" user "User.Eco1")
		(23 "Eco2.User" user "User.Eco2")
		(25 "Edge.Cuts" user "Board Geometry/Outline")
		(27 "Margin" user)
		(31 "F.CrtYd" user "Package Geometry/Place Bound Top")
		(29 "B.CrtYd" user "Package Geometry/Place Bound Bottom")
		(35 "F.Fab" user "Ref Des/Assembly Top")
		(33 "B.Fab" user "Ref Des/Assembly Bottom")
	)
	(footprint ""
		(layer "B.Cu")
		(at 104.716834 -250.892564 180)
		(property "Reference" "C2335"
			(at 0 0 0)
			(layer "B.SilkS")
			(hide yes)
			(effects
				(font
					(size 1.27 1.27)
				)
				(justify mirror)
			)
		)
		(property "Value" ""
			(at 0 0 0)
			(layer "B.Fab")
			(effects
				(font
					(size 1.27 1.27)
				)
				(justify mirror)
			)
		)
		(duplicate_pad_numbers_are_jumpers no)
		(fp_line
			(start 0.7874 0.4064)
			(end 0.7874 -0.4064)
			(stroke
				(width 0.1524)
				(type default)
			)
			(layer "B.SilkS")
		)
		(fp_line
			(start 0.7874 -0.4064)
			(end -0.7874 -0.4064)
			(stroke
				(width 0.1524)
				(type default)
			)
			(layer "B.SilkS")
		)
		(fp_line
			(start -0.7874 0.4064)
			(end 0.7874 0.4064)
			(stroke
				(width 0.1524)
				(type default)
			)
			(layer "B.SilkS")
		)
		(fp_line
			(start -0.7874 -0.4064)
			(end -0.7874 0.4064)
			(stroke
				(width 0.1524)
				(type default)
			)
			(layer "B.SilkS")
		)
		(fp_line
			(start 0.67945 0.3048)
			(end 0.67945 -0.305054)
			(stroke
				(width 0.1)
				(type default)
			)
			(layer "B.Fab")
		)
		(fp_line
			(start 0.67945 -0.305054)
			(end 0.12065 -0.305054)
			(stroke
				(width 0.1)
				(type default)
			)
			(layer "B.Fab")
		)
		(fp_line
			(start 0.12065 0.3048)
			(end 0.67945 0.3048)
			(stroke
				(width 0.1)
				(type default)
			)
			(layer "B.Fab")
		)
		(fp_line
			(start 0.12065 0.2794)
			(end 0.12065 0.3048)
			(stroke
				(width 0.1)
				(type default)
			)
			(layer "B.Fab")
		)
		(fp_line
			(start 0.12065 -0.2794)
			(end -0.12065 -0.2794)
			(stroke
				(width 0.1)
				(type default)
			)
			(layer "B.Fab")
		)
		(fp_line
			(start 0.12065 -0.305054)
			(end 0.12065 -0.2794)
			(stroke
				(width 0.1)
				(type default)
			)
			(layer "B.Fab")
		)
		(fp_line
			(start -0.120396 0.3048)
			(end -0.120396 0.2794)
			(stroke
				(width 0.1)
				(type default)
			)
			(layer "B.Fab")
		)
		(fp_line
			(start -0.120396 0.2794)
			(end 0.12065 0.2794)
			(stroke
				(width 0.1)
				(type default)
			)
			(layer "B.Fab")
		)
		(fp_line
			(start -0.12065 -0.2794)
			(end -0.12065 -0.3048)
			(stroke
				(width 0.1)
				(type default)
			)
			(layer "B.Fab")
		)
		(fp_line
			(start -0.12065 -0.3048)
			(end -0.67945 -0.3048)
			(stroke
				(width 0.1)
				(type default)
			)
			(layer "B.Fab")
		)
		(fp_line
			(start -0.67945 0.3048)
			(end -0.120396 0.3048)
			(stroke
				(width 0.1)
				(type default)
			)
			(layer "B.Fab")
		)
		(fp_line
			(start -0.67945 -0.3048)
			(end -0.67945 0.3048)
			(stroke
				(width 0.1)
				(type default)
			)
			(layer "B.Fab")
		)
		(pad "1" smd circle
			(at 0.40005 0)
			(size 0 0)
			(layers "B.Cu" "B.Mask" "B.Paste")
			(net "PVDDCR_CPU0_P1")
		)
		(pad "2" smd circle
			(at -0.40005 0)
			(size 0 0)
			(layers "B.Cu" "B.Mask" "B.Paste")
			(net "GND")
		)
	)
	(footprint ""
		(layer "B.Cu")
		(at 101.512878 -139.93241 90)
		(property "Reference" "PC252"
			(at 0 0 90)
			(layer "B.SilkS")
			(hide yes)
			(effects
				(font
					(size 1.27 1.27)
				)
				(justify mirror)
			)
		)
		(property "Value" ""
			(at 0 0 90)
			(layer "B.Fab")
			(effects
				(font
					(size 1.27 1.27)
				)
				(justify mirror)
			)
		)
		(duplicate_pad_numbers_are_jumpers no)
		(fp_line
			(start 0.7874 -0.4064)
			(end -0.7874 -0.4064)
			(stroke
				(width 0.1524)
				(type default)
			)
			(layer "B.SilkS")
		)
		(fp_line
			(start -0.7874 -0.4064)
			(end -0.7874 0.4064)
			(stroke
				(width 0.1524)
				(type default)
			)
			(layer "B.SilkS")
		)
		(fp_line
			(start 0.7874 0.4064)
			(end 0.7874 -0.4064)
			(stroke
				(width 0.1524)
				(type default)
			)
			(layer "B.SilkS")
		)
		(fp_line
			(start -0.7874 0.4064)
			(end 0.7874 0.4064)
			(stroke
				(width 0.1524)
				(type default)
			)
			(layer "B.SilkS")
		)
		(fp_line
			(start 0.67945 -0.305054)
			(end 0.12065 -0.305054)
			(stroke
				(width 0.1)
				(type default)
			)
			(layer "B.Fab")
		)
		(fp_line
			(start 0.12065 -0.305054)
			(end 0.12065 -0.2794)
			(stroke
				(width 0.1)
				(type default)
			)
			(layer "B.Fab")
		)
		(fp_line
			(start -0.12065 -0.3048)
			(end -0.67945 -0.3048)
			(stroke
				(width 0.1)
				(type default)
			)
			(layer "B.Fab")
		)
		(fp_line
			(start -0.67945 -0.3048)
			(end -0.67945 0.3048)
			(stroke
				(width 0.1)
				(type default)
			)
			(layer "B.Fab")
		)
		(fp_line
			(start 0.12065 -0.2794)
			(end -0.12065 -0.2794)
			(stroke
				(width 0.1)
				(type default)
			)
			(layer "B.Fab")
		)
		(fp_line
			(start -0.12065 -0.2794)
			(end -0.12065 -0.3048)
			(stroke
				(width 0.1)
				(type default)
			)
			(layer "B.Fab")
		)
		(fp_line
			(start 0.12065 0.2794)
			(end 0.12065 0.3048)
			(stroke
				(width 0.1)
				(type default)
			)
			(layer "B.Fab")
		)
		(fp_line
			(start -0.120396 0.2794)
			(end 0.12065 0.2794)
			(stroke
				(width 0.1)
				(type default)
			)
			(layer "B.Fab")
		)
		(fp_line
			(start 0.67945 0.3048)
			(end 0.67945 -0.305054)
			(stroke
				(width 0.1)
				(type default)
			)
			(layer "B.Fab")
		)
		(fp_line
			(start 0.12065 0.3048)
			(end 0.67945 0.3048)
			(stroke
				(width 0.1)
				(type default)
			)
			(layer "B.Fab")
		)
		(fp_line
			(start -0.120396 0.3048)
			(end -0.120396 0.2794)
			(stroke
				(width 0.1)
				(type default)
			)
			(layer "B.Fab")
		)
		(fp_line
			(start -0.67945 0.3048)
			(end -0.120396 0.3048)
			(stroke
				(width 0.1)
				(type default)
			)
			(layer "B.Fab")
		)
		(pad "1" smd circle
			(at 0.40005 0 270)
			(size 0 0)
			(layers "B.Cu" "B.Mask" "B.Paste")
			(net "PVDDCR_CPU0_P1_VCC")
		)
		(pad "2" smd circle
			(at -0.40005 0 270)
			(size 0 0)
			(layers "B.Cu" "B.Mask" "B.Paste")
			(net "GND")
		)
	)
	(footprint ""
		(layer "B.Cu")
		(at 149.884638 -13.762228 90)
		(property "Reference" "R2418"
			(at 0 0 90)
			(layer "B.SilkS")
			(hide yes)
			(effects
				(font
					(size 1.27 1.27)
				)
				(justify mirror)
			)
		)
		(property "Value" ""
			(at 0 0 90)
			(layer "B.Fab")
			(effects
				(font
					(size 1.27 1.27)
				)
				(justify mirror)
			)
		)
		(duplicate_pad_numbers_are_jumpers no)
		(fp_line
			(start 0.7874 -0.4064)
			(end -0.7874 -0.4064)
			(stroke
				(width 0.1524)
				(type default)
			)
			(layer "B.SilkS")
		)
		(fp_line
			(start -0.7874 -0.4064)
			(end -0.7874 0.4064)
			(stroke
				(width 0.1524)
				(type default)
			)
			(layer "B.SilkS")
		)
		(fp_line
			(start 0.7874 0.4064)
			(end 0.7874 -0.4064)
			(stroke
				(width 0.1524)
				(type default)
			)
			(layer "B.SilkS")
		)
		(fp_line
			(start -0.7874 0.4064)
			(end 0.7874 0.4064)
			(stroke
				(width 0.1524)
				(type default)
			)
			(layer "B.SilkS")
		)
		(fp_line
			(start 0.67945 -0.305054)
			(end 0.12065 -0.305054)
			(stroke
				(width 0.1)
				(type default)
			)
			(layer "B.Fab")
		)
		(fp_line
			(start 0.12065 -0.305054)
			(end 0.12065 -0.2794)
			(stroke
				(width 0.1)
				(type default)
			)
			(layer "B.Fab")
		)
		(fp_line
			(start -0.12065 -0.3048)
			(end -0.67945 -0.3048)
			(stroke
				(width 0.1)
				(type default)
			)
			(layer "B.Fab")
		)
		(fp_line
			(start -0.67945 -0.3048)
			(end -0.67945 0.3048)
			(stroke
				(width 0.1)
				(type default)
			)
			(layer "B.Fab")
		)
		(fp_line
			(start 0.12065 -0.2794)
			(end -0.12065 -0.2794)
			(stroke
				(width 0.1)
				(type default)
			)
			(layer "B.Fab")
		)
		(fp_line
			(start -0.12065 -0.2794)
			(end -0.12065 -0.3048)
			(stroke
				(width 0.1)
				(type default)
			)
			(layer "B.Fab")
		)
		(fp_line
			(start 0.12065 0.2794)
			(end 0.12065 0.3048)
			(stroke
				(width 0.1)
				(type default)
			)
			(layer "B.Fab")
		)
		(fp_line
			(start -0.120396 0.2794)
			(end 0.12065 0.2794)
			(stroke
				(width 0.1)
				(type default)
			)
			(layer "B.Fab")
		)
		(fp_line
			(start 0.67945 0.3048)
			(end 0.67945 -0.305054)
			(stroke
				(width 0.1)
				(type default)
			)
			(layer "B.Fab")
		)
		(fp_line
			(start 0.12065 0.3048)
			(end 0.67945 0.3048)
			(stroke
				(width 0.1)
				(type default)
			)
			(layer "B.Fab")
		)
		(fp_line
			(start -0.120396 0.3048)
			(end -0.120396 0.2794)
			(stroke
				(width 0.1)
				(type default)
			)
			(layer "B.Fab")
		)
		(fp_line
			(start -0.67945 0.3048)
			(end -0.120396 0.3048)
			(stroke
				(width 0.1)
				(type default)
			)
			(layer "B.Fab")
		)
		(pad "1" smd circle
			(at 0.40005 0 270)
			(size 0 0)
			(layers "B.Cu" "B.Mask" "B.Paste")
			(net "SMB_HOST_CLK_3V3AUX_SDA")
		)
		(pad "2" smd circle
			(at -0.40005 0 270)
			(size 0 0)
			(layers "B.Cu" "B.Mask" "B.Paste")
			(net "SMB_HOST_CLK_3V3AUX_SDA_R0")
		)
	)
	(footprint ""
		(layer "B.Cu")
		(at 280.041096 -349.381572 -90)
		(property "Reference" "PR111"
			(at 0 0 90)
			(layer "B.SilkS")
			(hide yes)
			(effects
				(font
					(size 1.27 1.27)
				)
				(justify mirror)
			)
		)
		(property "Value" ""
			(at 0 0 90)
			(layer "B.Fab")
			(effects
				(font
					(size 1.27 1.27)
				)
				(justify mirror)
			)
		)
		(duplicate_pad_numbers_are_jumpers no)
		(fp_line
			(start -0.7874 0.4064)
			(end 0.7874 0.4064)
			(stroke
				(width 0.1524)
				(type default)
			)
			(layer "B.SilkS")
		)
		(fp_line
			(start 0.7874 0.4064)
			(end 0.7874 -0.4064)
			(stroke
				(width 0.1524)
				(type default)
			)
			(layer "B.SilkS")
		)
		(fp_line
			(start -0.7874 -0.4064)
			(end -0.7874 0.4064)
			(stroke
				(width 0.1524)
				(type default)
			)
			(layer "B.SilkS")
		)
		(fp_line
			(start 0.7874 -0.4064)
			(end -0.7874 -0.4064)
			(stroke
				(width 0.1524)
				(type default)
			)
			(layer "B.SilkS")
		)
		(fp_line
			(start -0.67945 0.3048)
			(end -0.120396 0.3048)
			(stroke
				(width 0.1)
				(type default)
			)
			(layer "B.Fab")
		)
		(fp_line
			(start -0.120396 0.3048)
			(end -0.120396 0.2794)
			(stroke
				(width 0.1)
				(type default)
			)
			(layer "B.Fab")
		)
		(fp_line
			(start 0.12065 0.3048)
			(end 0.67945 0.3048)
			(stroke
				(width 0.1)
				(type default)
			)
			(layer "B.Fab")
		)
		(fp_line
			(start 0.67945 0.3048)
			(end 0.67945 -0.305054)
			(stroke
				(width 0.1)
				(type default)
			)
			(layer "B.Fab")
		)
		(fp_line
			(start -0.120396 0.2794)
			(end 0.12065 0.2794)
			(stroke
				(width 0.1)
				(type default)
			)
			(layer "B.Fab")
		)
		(fp_line
			(start 0.12065 0.2794)
			(end 0.12065 0.3048)
			(stroke
				(width 0.1)
				(type default)
			)
			(layer "B.Fab")
		)
		(fp_line
			(start -0.12065 -0.2794)
			(end -0.12065 -0.3048)
			(stroke
				(width 0.1)
				(type default)
			)
			(layer "B.Fab")
		)
		(fp_line
			(start 0.12065 -0.2794)
			(end -0.12065 -0.2794)
			(stroke
				(width 0.1)
				(type default)
			)
			(layer "B.Fab")
		)
		(fp_line
			(start -0.67945 -0.3048)
			(end -0.67945 0.3048)
			(stroke
				(width 0.1)
				(type default)
			)
			(layer "B.Fab")
		)
		(fp_line
			(start -0.12065 -0.3048)
			(end -0.67945 -0.3048)
			(stroke
				(width 0.1)
				(type default)
			)
			(layer "B.Fab")
		)
		(fp_line
			(start 0.12065 -0.305054)
			(end 0.12065 -0.2794)
			(stroke
				(width 0.1)
				(type default)
			)
			(layer "B.Fab")
		)
		(fp_line
			(start 0.67945 -0.305054)
			(end 0.12065 -0.305054)
			(stroke
				(width 0.1)
				(type default)
			)
			(layer "B.Fab")
		)
		(pad "1" smd circle
			(at 0.40005 0 90)
			(size 0 0)
			(layers "B.Cu" "B.Mask" "B.Paste")
			(net "PVDDIO_P0_VOS3")
		)
		(pad "2" smd circle
			(at -0.40005 0 90)
			(size 0 0)
			(layers "B.Cu" "B.Mask" "B.Paste")
			(net "PVDDIO_P0")
		)
	)
	(footprint ""
		(layer "B.Cu")
		(at 352.846132 -396.393162 -90)
		(property "Reference" "C631"
			(at 0 0 90)
			(layer "B.SilkS")
			(hide yes)
			(effects
				(font
					(size 1.27 1.27)
				)
				(justify mirror)
			)
		)
		(property "Value" ""
			(at 0 0 90)
			(layer "B.Fab")
			(effects
				(font
					(size 1.27 1.27)
				)
				(justify mirror)
			)
		)
		(duplicate_pad_numbers_are_jumpers no)
		(fp_line
			(start -0.299974 0.150114)
			(end 0.299974 0.150114)
			(stroke
				(width 0.1)
				(type default)
			)
			(layer "B.Fab")
		)
		(fp_line
			(start 0.299974 0.150114)
			(end 0.299974 -0.150114)
			(stroke
				(width 0.1)
				(type default)
			)
			(layer "B.Fab")
		)
		(fp_line
			(start -0.299974 -0.150114)
			(end -0.299974 0.150114)
			(stroke
				(width 0.1)
				(type default)
			)
			(layer "B.Fab")
		)
		(fp_line
			(start 0.299974 -0.150114)
			(end -0.299974 -0.150114)
			(stroke
				(width 0.1)
				(type default)
			)
			(layer "B.Fab")
		)
		(pad "1" smd rect
			(at 0.2667 0 90)
			(size 0.3048 0.381)
			(layers "B.Cu" "B.Mask" "B.Paste")
			(net "P0V9_CPU0_RT1_2A")
		)
		(pad "2" smd rect
			(at -0.2667 0 90)
			(size 0.3048 0.381)
			(layers "B.Cu" "B.Mask" "B.Paste")
			(net "GND")
		)
	)
	(footprint ""
		(layer "B.Cu")
		(at 17.608042 -192.66027 180)
		(property "Reference" "C518"
			(at 0 0 0)
			(layer "B.SilkS")
			(hide yes)
			(effects
				(font
					(size 1.27 1.27)
				)
				(justify mirror)
			)
		)
		(property "Value" ""
			(at 0 0 0)
			(layer "B.Fab")
			(effects
				(font
					(size 1.27 1.27)
				)
				(justify mirror)
			)
		)
		(duplicate_pad_numbers_are_jumpers no)
		(fp_line
			(start 1.524 0.762)
			(end 1.524 -0.762)
			(stroke
				(width 0.1524)
				(type default)
			)
			(layer "B.SilkS")
		)
		(fp_line
			(start 1.524 -0.762)
			(end -1.524 -0.762)
			(stroke
				(width 0.1524)
				(type default)
			)
			(layer "B.SilkS")
		)
		(fp_line
			(start -1.524 0.762)
			(end 1.524 0.762)
			(stroke
				(width 0.1524)
				(type default)
			)
			(layer "B.SilkS")
		)
		(fp_line
			(start -1.524 -0.762)
			(end -1.524 0.762)
			(stroke
				(width 0.1524)
				(type default)
			)
			(layer "B.SilkS")
		)
		(fp_line
			(start 1.1049 0.724916)
			(end -1.1049 0.724916)
			(stroke
				(width 0.1)
				(type default)
			)
			(layer "B.Fab")
		)
		(fp_line
			(start 1.1049 -0.724916)
			(end 1.1049 0.724916)
			(stroke
				(width 0.1)
				(type default)
			)
			(layer "B.Fab")
		)
		(fp_line
			(start -1.1049 0.724916)
			(end -1.1049 -0.724916)
			(stroke
				(width 0.1)
				(type default)
			)
			(layer "B.Fab")
		)
		(fp_line
			(start -1.1049 -0.724916)
			(end 1.1049 -0.724916)
			(stroke
				(width 0.1)
				(type default)
			)
			(layer "B.Fab")
		)
		(pad "1" smd rect
			(at 0.889 0 180)
			(size 1.016 1.27)
			(layers "B.Cu" "B.Mask" "B.Paste")
			(net "P12V_MEM_CPU1")
		)
		(pad "2" smd rect
			(at -0.889 0 180)
			(size 1.016 1.27)
			(layers "B.Cu" "B.Mask" "B.Paste")
			(net "GND")
		)
	)
	(footprint ""
		(layer "B.Cu")
		(at 62.996318 -350.660716 -90)
		(property "Reference" "PC415_4"
			(at 0 0 90)
			(layer "B.SilkS")
			(hide yes)
			(effects
				(font
					(size 1.27 1.27)
				)
				(justify mirror)
			)
		)
		(property "Value" ""
			(at 0 0 90)
			(layer "B.Fab")
			(effects
				(font
					(size 1.27 1.27)
				)
				(justify mirror)
			)
		)
		(duplicate_pad_numbers_are_jumpers no)
		(fp_line
			(start -1.524 0.762)
			(end 1.524 0.762)
			(stroke
				(width 0.1524)
				(type default)
			)
			(layer "B.SilkS")
		)
		(fp_line
			(start 1.524 0.762)
			(end 1.524 -0.762)
			(stroke
				(width 0.1524)
				(type default)
			)
			(layer "B.SilkS")
		)
		(fp_line
			(start -1.524 -0.762)
			(end -1.524 0.762)
			(stroke
				(width 0.1524)
				(type default)
			)
			(layer "B.SilkS")
		)
		(fp_line
			(start 1.524 -0.762)
			(end -1.524 -0.762)
			(stroke
				(width 0.1524)
				(type default)
			)
			(layer "B.SilkS")
		)
		(fp_line
			(start -1.1049 0.724916)
			(end -1.1049 -0.724916)
			(stroke
				(width 0.1)
				(type default)
			)
			(layer "B.Fab")
		)
		(fp_line
			(start 1.1049 0.724916)
			(end -1.1049 0.724916)
			(stroke
				(width 0.1)
				(type default)
			)
			(layer "B.Fab")
		)
		(fp_line
			(start -1.1049 -0.724916)
			(end 1.1049 -0.724916)
			(stroke
				(width 0.1)
				(type default)
			)
			(layer "B.Fab")
		)
		(fp_line
			(start 1.1049 -0.724916)
			(end 1.1049 0.724916)
			(stroke
				(width 0.1)
				(type default)
			)
			(layer "B.Fab")
		)
		(pad "1" smd rect
			(at 0.889 0 270)
			(size 1.016 1.27)
			(layers "B.Cu" "B.Mask" "B.Paste")
			(net "SW_P12V_AUX_PVDDCR_CPU1_P1_FLT")
		)
		(pad "2" smd rect
			(at -0.889 0 270)
			(size 1.016 1.27)
			(layers "B.Cu" "B.Mask" "B.Paste")
			(net "GND")
		)
	)
	(footprint ""
		(layer "B.Cu")
		(at 117.351302 -165.040056 -90)
		(property "Reference" "PC8012"
			(at 0 0 90)
			(layer "B.SilkS")
			(hide yes)
			(effects
				(font
					(size 1.27 1.27)
				)
				(justify mirror)
			)
		)
		(property "Value" ""
			(at 0 0 90)
			(layer "B.Fab")
			(effects
				(font
					(size 1.27 1.27)
				)
				(justify mirror)
			)
		)
		(duplicate_pad_numbers_are_jumpers no)
		(fp_line
			(start -1.524 0.762)
			(end 1.524 0.762)
			(stroke
				(width 0.1524)
				(type default)
			)
			(layer "B.SilkS")
		)
		(fp_line
			(start 1.524 0.762)
			(end 1.524 -0.762)
			(stroke
				(width 0.1524)
				(type default)
			)
			(layer "B.SilkS")
		)
		(fp_line
			(start -1.524 -0.762)
			(end -1.524 0.762)
			(stroke
				(width 0.1524)
				(type default)
			)
			(layer "B.SilkS")
		)
		(fp_line
			(start 1.524 -0.762)
			(end -1.524 -0.762)
			(stroke
				(width 0.1524)
				(type default)
			)
			(layer "B.SilkS")
		)
		(fp_line
			(start -1.1049 0.724916)
			(end -1.1049 -0.724916)
			(stroke
				(width 0.1)
				(type default)
			)
			(layer "B.Fab")
		)
		(fp_line
			(start 1.1049 0.724916)
			(end -1.1049 0.724916)
			(stroke
				(width 0.1)
				(type default)
			)
			(layer "B.Fab")
		)
		(fp_line
			(start -1.1049 -0.724916)
			(end 1.1049 -0.724916)
			(stroke
				(width 0.1)
				(type default)
			)
			(layer "B.Fab")
		)
		(fp_line
			(start 1.1049 -0.724916)
			(end 1.1049 0.724916)
			(stroke
				(width 0.1)
				(type default)
			)
			(layer "B.Fab")
		)
		(pad "1" smd rect
			(at 0.889 0 270)
			(size 1.016 1.27)
			(layers "B.Cu" "B.Mask" "B.Paste")
			(net "SW_P12V_AUX_PVDDCR_SOC_P1_FLT")
		)
		(pad "2" smd rect
			(at -0.889 0 270)
			(size 1.016 1.27)
			(layers "B.Cu" "B.Mask" "B.Paste")
			(net "GND")
		)
	)
)
